# S9S_MB_2U (Grand Teton) — schematic netlist excerpt (pin names and nets, part order shuffled) for the footprints in the layout excerpt that follows; sources: Cadence DE-HDL packaged netlist, KiCad conversion of 03242023_DA0F0TMBIJ0_F0T_Motherboard_J_brd_V01_OCP.brd

J118  PICOPROBE_BXA  DELTA-L 4.0 EMPTY  pkg TRIANG_LAUNCH_3PXB  page 308
  \1_p\  = DELTA_L_85_10INCH_IN5_DP
  \2_n\  = DELTA_L_85_10INCH_IN5_DN
  \3_g\  = DELTA_L_GND_1

(kicad_pcb
	(version 20260206)
	(generator "pcbnew")
	(generator_version "10.0")
	(general
		(thickness 1.6)
		(legacy_teardrops no)
	)
	(paper "A4")
	(title_block
		(title "03242023_DA0F0TMBIJ0_F0T_Motherboard_J_brd_V01_OCP.brd")
		(comment 1 "Grand Teton / footprints 4751-4751 of 6105")
	)
	(layers
		(0 "F.Cu" signal "TOP")
		(4 "In1.Cu" signal "GND")
		(6 "In2.Cu" signal "IN1")
		(8 "In3.Cu" signal "GND1")
		(10 "In4.Cu" signal "IN2")
		(12 "In5.Cu" signal "GND2")
		(14 "In6.Cu" signal "IN3")
		(16 "In7.Cu" signal "GND3")
		(18 "In8.Cu" signal "VCC")
		(20 "In9.Cu" signal "VCC1")
		(22 "In10.Cu" signal "GND4")
		(24 "In11.Cu" signal "IN4")
		(26 "In12.Cu" signal "GND5")
		(28 "In13.Cu" signal "IN5")
		(30 "In14.Cu" signal "GND6")
		(32 "In15.Cu" signal "IN6")
		(34 "In16.Cu" signal "GND7")
		(2 "B.Cu" signal "BOTTOM")
		(9 "F.Adhes" user "F.Adhesive")
		(11 "B.Adhes" user "B.Adhesive")
		(13 "F.Paste" user "Package Geometry/Pastemask Top")
		(15 "B.Paste" user "Package Geometry/Pastemask Bottom")
		(5 "F.SilkS" user "Ref Des/Silkscreen Top")
		(7 "B.SilkS" user "Ref Des/Silkscreen Bottom")
		(1 "F.Mask" user "Board Geometry/Soldermask Top")
		(3 "B.Mask" user "Board Geometry/Soldermask Bottom")
		(17 "Dwgs.User" user "User.Drawings")
		(19 "Cmts.User" user "User.Comments")
		(21 "Eco1.User" user "User.Eco1")
		(23 "Eco2.User" user "User.Eco2")
		(25 "Edge.Cuts" user "Board Geometry/Outline")
		(27 "Margin" user)
		(31 "F.CrtYd" user "Package Geometry/Place Bound Top")
		(29 "B.CrtYd" user "Package Geometry/Place Bound Bottom")
		(35 "F.Fab" user "Ref Des/Assembly Top")
		(33 "B.Fab" user "Ref Des/Assembly Bottom")
	)
	(footprint ""
		(layer "B.Cu")
		(at 260.731508 8.003794 180)
		(property "Reference" "J118"
			(at 4.345178 -1.648206 270)
			(unlocked yes)
			(layer "B.SilkS")
			(effects
				(font
					(size 0.7874 0.5842)
					(thickness 0.1524)
				)
				(justify left mirror)
			)
		)
		(property "Value" ""
			(at 0 0 0)
			(layer "B.Fab")
			(effects
				(font
					(size 1.27 1.27)
				)
				(justify mirror)
			)
		)
		(duplicate_pad_numbers_are_jumpers no)
		(fp_line
			(start 1.2192 2.1082)
			(end 1.2192 -2.1082)
			(stroke
				(width 0.1524)
				(type default)
			)
			(layer "B.SilkS")
		)
		(fp_line
			(start 1.2192 -2.1082)
			(end -1.2192 -2.1082)
			(stroke
				(width 0.1524)
				(type default)
			)
			(layer "B.SilkS")
		)
		(fp_line
			(start -1.2192 2.1082)
			(end 1.2192 2.1082)
			(stroke
				(width 0.1524)
				(type default)
			)
			(layer "B.SilkS")
		)
		(fp_line
			(start -1.2192 -2.1082)
			(end -1.2192 2.1082)
			(stroke
				(width 0.1524)
				(type default)
			)
			(layer "B.SilkS")
		)
		(pad "" np_thru_hole circle
			(at -3.4671 -1.27 90)
			(size 1.0414 1.0414)
			(drill 1.0414)
			(layers "*.Cu" "*.Mask")
			(clearance 0.381)
			(thermal_gap 0.381)
		)
		(pad "" np_thru_hole circle
			(at -3.4671 1.27 90)
			(size 1.0414 1.0414)
			(drill 1.0414)
			(layers "*.Cu" "*.Mask")
			(clearance 0.381)
			(thermal_gap 0.381)
		)
		(pad "" np_thru_hole circle
			(at 2.8829 -1.27 90)
			(size 1.0414 1.0414)
			(drill 1.0414)
			(layers "*.Cu" "*.Mask")
			(clearance 0.381)
			(thermal_gap 0.381)
		)
		(pad "" np_thru_hole circle
			(at 2.8829 1.27 90)
			(size 1.0414 1.0414)
			(drill 1.0414)
			(layers "*.Cu" "*.Mask")
			(clearance 0.381)
			(thermal_gap 0.381)
		)
		(pad "1" smd rect
			(at -0.8255 -0.249936 90)
			(size 0.3048 0.508)
			(layers "B.Cu" "B.Mask" "B.Paste")
			(net "DELTA_L_85_10INCH_IN5_DP")
		)
		(pad "2" smd rect
			(at -0.8255 0.249936 90)
			(size 0.3048 0.508)
			(layers "B.Cu" "B.Mask" "B.Paste")
			(net "DELTA_L_85_10INCH_IN5_DN")
		)
		(pad "3" smd circle
			(at 0 0)
			(size 0 0)
			(layers "B.Cu" "B.Mask" "B.Paste")
			(net "DELTA_L_GND_1")
		)
		(zone
			(layers "F.Cu" "B.Cu" "In1.Cu" "In2.Cu" "In3.Cu" "In4.Cu" "In5.Cu" "In6.Cu"
				"In7.Cu" "In8.Cu" "In9.Cu" "In10.Cu" "In11.Cu" "In12.Cu" "In13.Cu" "In14.Cu"
				"In15.Cu" "In16.Cu"
			)
			(hatch none 0.5)
			(connect_pads
				(clearance 0)
			)
			(min_thickness 0.25)
			(keepout
				(tracks not_allowed)
				(vias allowed)
				(pads allowed)
				(copperpour not_allowed)
				(footprints allowed)
			)
			(placement
				(enabled no)
				(sheetname "")
			)
			(fill
				(thermal_gap 0.5)
				(thermal_bridge_width 0.5)
				(island_removal_mode 0)
			)
			(polygon
				(pts
					(arc
						(start 258.775708 6.733794)
						(mid 256.921508 6.733794)
						(end 258.775708 6.733794)
					)
				)
			)
		)
		(zone
			(layers "F.Cu" "B.Cu" "In1.Cu" "In2.Cu" "In3.Cu" "In4.Cu" "In5.Cu" "In6.Cu"
				"In7.Cu" "In8.Cu" "In9.Cu" "In10.Cu" "In11.Cu" "In12.Cu" "In13.Cu" "In14.Cu"
				"In15.Cu" "In16.Cu"
			)
			(hatch none 0.5)
			(connect_pads
				(clearance 0)
			)
			(min_thickness 0.25)
			(keepout
				(tracks not_allowed)
				(vias allowed)
				(pads allowed)
				(copperpour not_allowed)
				(footprints allowed)
			)
			(placement
				(enabled no)
				(sheetname "")
			)
			(fill
				(thermal_gap 0.5)
				(thermal_bridge_width 0.5)
				(island_removal_mode 0)
			)
			(polygon
				(pts
					(arc
						(start 258.775708 9.273794)
						(mid 256.921508 9.273794)
						(end 258.775708 9.273794)
					)
				)
			)
		)
		(zone
			(layers "F.Cu" "B.Cu" "In1.Cu" "In2.Cu" "In3.Cu" "In4.Cu" "In5.Cu" "In6.Cu"
				"In7.Cu" "In8.Cu" "In9.Cu" "In10.Cu" "In11.Cu" "In12.Cu" "In13.Cu" "In14.Cu"
				"In15.Cu" "In16.Cu"
			)
			(hatch none 0.5)
			(connect_pads
				(clearance 0)
			)
			(min_thickness 0.25)
			(keepout
				(tracks not_allowed)
				(vias allowed)
				(pads allowed)
				(copperpour not_allowed)
				(footprints allowed)
			)
			(placement
				(enabled no)
				(sheetname "")
			)
			(fill
				(thermal_gap 0.5)
				(thermal_bridge_width 0.5)
				(island_removal_mode 0)
			)
			(polygon
				(pts
					(arc
						(start 265.125708 6.733794)
						(mid 263.271508 6.733794)
						(end 265.125708 6.733794)
					)
				)
			)
		)
		(zone
			(layers "F.Cu" "B.Cu" "In1.Cu" "In2.Cu" "In3.Cu" "In4.Cu" "In5.Cu" "In6.Cu"
				"In7.Cu" "In8.Cu" "In9.Cu" "In10.Cu" "In11.Cu" "In12.Cu" "In13.Cu" "In14.Cu"
				"In15.Cu" "In16.Cu"
			)
			(hatch none 0.5)
			(connect_pads
				(clearance 0)
			)
			(min_thickness 0.25)
			(keepout
				(tracks not_allowed)
				(vias allowed)
				(pads allowed)
				(copperpour not_allowed)
				(footprints allowed)
			)
			(placement
				(enabled no)
				(sheetname "")
			)
			(fill
				(thermal_gap 0.5)
				(thermal_bridge_width 0.5)
				(island_removal_mode 0)
			)
			(polygon
				(pts
					(arc
						(start 265.125708 9.273794)
						(mid 263.271508 9.273794)
						(end 265.125708 9.273794)
					)
				)
			)
		)
		(zone
			(layer "B.Cu")
			(hatch none 0.5)
			(connect_pads
				(clearance 0)
			)
			(min_thickness 0.25)
			(keepout
				(tracks not_allowed)
				(vias allowed)
				(pads allowed)
				(copperpour not_allowed)
				(footprints allowed)
			)
			(placement
				(enabled no)
				(sheetname "")
			)
			(fill
				(thermal_gap 0.5)
				(thermal_bridge_width 0.5)
				(island_removal_mode 0)
			)
			(polygon
				(pts
					(xy 261.849108 8.552434) (xy 261.849108 8.45693) (xy 261.252208 8.45693) (xy 261.252208 8.05053)
					(xy 261.849108 8.05053) (xy 261.849108 7.957058) (xy 261.252208 7.957058) (xy 261.252208 7.550658)
					(xy 261.849108 7.550658) (xy 261.849108 7.455154) (xy 261.150608 7.455154) (xy 261.150608 8.552434)
				)
			)
		)
	)
)
